# S9S_MB_2U (Grand Teton) — schematic netlist excerpt (pin names and nets, part order shuffled) for the footprints in the layout excerpt that follows; sources: Cadence DE-HDL packaged netlist, KiCad conversion of 03242023_DA0F0TMBIJ0_F0T_Motherboard_J_brd_V01_OCP.brd

PJ64  Q_SHORT  EMPTY  pkg SM  page 281 : \1\ = SH_PVPP_HBM_CPU0_P ; \2\ = PVPP_HBM_CPU0
C1407  Q_CAP  47UF 2.5V 20% X6S  pkg C0603  page 75 : A = PVNN_MAIN_CPU0 ; B = GND
R2584  Q_RES  10K 1% CHIP  pkg 0402LF  page 300 : A = P3V3_AUX ; B = PWRGD_PVNN_MAIN_CPU1_R

(kicad_pcb
	(version 20260206)
	(generator "pcbnew")
	(generator_version "10.0")
	(general
		(thickness 1.6)
		(legacy_teardrops no)
	)
	(paper "A4")
	(title_block
		(title "03242023_DA0F0TMBIJ0_F0T_Motherboard_J_brd_V01_OCP.brd")
		(comment 1 "Grand Teton / footprints 4974-4976 of 6105")
	)
	(layers
		(0 "F.Cu" signal "TOP")
		(4 "In1.Cu" signal "GND")
		(6 "In2.Cu" signal "IN1")
		(8 "In3.Cu" signal "GND1")
		(10 "In4.Cu" signal "IN2")
		(12 "In5.Cu" signal "GND2")
		(14 "In6.Cu" signal "IN3")
		(16 "In7.Cu" signal "GND3")
		(18 "In8.Cu" signal "VCC")
		(20 "In9.Cu" signal "VCC1")
		(22 "In10.Cu" signal "GND4")
		(24 "In11.Cu" signal "IN4")
		(26 "In12.Cu" signal "GND5")
		(28 "In13.Cu" signal "IN5")
		(30 "In14.Cu" signal "GND6")
		(32 "In15.Cu" signal "IN6")
		(34 "In16.Cu" signal "GND7")
		(2 "B.Cu" signal "BOTTOM")
		(9 "F.Adhes" user "F.Adhesive")
		(11 "B.Adhes" user "B.Adhesive")
		(13 "F.Paste" user "Package Geometry/Pastemask Top")
		(15 "B.Paste" user "Package Geometry/Pastemask Bottom")
		(5 "F.SilkS" user "Ref Des/Silkscreen Top")
		(7 "B.SilkS" user "Ref Des/Silkscreen Bottom")
		(1 "F.Mask" user "Board Geometry/Soldermask Top")
		(3 "B.Mask" user "Board Geometry/Soldermask Bottom")
		(17 "Dwgs.User" user "User.Drawings")
		(19 "Cmts.User" user "User.Comments")
		(21 "Eco1.User" user "User.Eco1")
		(23 "Eco2.User" user "User.Eco2")
		(25 "Edge.Cuts" user "Board Geometry/Outline")
		(27 "Margin" user)
		(31 "F.CrtYd" user "Package Geometry/Place Bound Top")
		(29 "B.CrtYd" user "Package Geometry/Place Bound Bottom")
		(35 "F.Fab" user "Ref Des/Assembly Top")
		(33 "B.Fab" user "Ref Des/Assembly Bottom")
	)
	(footprint ""
		(layer "B.Cu")
		(at 351.536508 -237.709202 -90)
		(property "Reference" "C1407"
			(at 0 0 90)
			(layer "B.SilkS")
			(hide yes)
			(effects
				(font
					(size 1.27 1.27)
				)
				(justify mirror)
			)
		)
		(property "Value" ""
			(at 0 0 90)
			(layer "B.Fab")
			(effects
				(font
					(size 1.27 1.27)
				)
				(justify mirror)
			)
		)
		(duplicate_pad_numbers_are_jumpers no)
		(fp_line
			(start -1.2954 0.5842)
			(end 1.2954 0.5842)
			(stroke
				(width 0.1524)
				(type default)
			)
			(layer "B.SilkS")
		)
		(fp_line
			(start 1.2954 0.5842)
			(end 1.2954 -0.5842)
			(stroke
				(width 0.1524)
				(type default)
			)
			(layer "B.SilkS")
		)
		(fp_line
			(start -1.2954 -0.5842)
			(end -1.2954 0.5842)
			(stroke
				(width 0.1524)
				(type default)
			)
			(layer "B.SilkS")
		)
		(fp_line
			(start 0 -0.5842)
			(end 0 0.5842)
			(stroke
				(width 0.1524)
				(type default)
			)
			(layer "B.SilkS")
		)
		(fp_line
			(start 1.2954 -0.5842)
			(end -1.2954 -0.5842)
			(stroke
				(width 0.1524)
				(type default)
			)
			(layer "B.SilkS")
		)
		(fp_line
			(start -0.8636 0.4572)
			(end 0.8636 0.4572)
			(stroke
				(width 0.1)
				(type default)
			)
			(layer "B.Fab")
		)
		(fp_line
			(start 0.8636 0.4572)
			(end 0.8636 0.4064)
			(stroke
				(width 0.1)
				(type default)
			)
			(layer "B.Fab")
		)
		(fp_line
			(start -1.1938 0.4064)
			(end -0.8636 0.4064)
			(stroke
				(width 0.1)
				(type default)
			)
			(layer "B.Fab")
		)
		(fp_line
			(start -0.8636 0.4064)
			(end -0.8636 0.4572)
			(stroke
				(width 0.1)
				(type default)
			)
			(layer "B.Fab")
		)
		(fp_line
			(start 0.8636 0.4064)
			(end 1.1938 0.4064)
			(stroke
				(width 0.1)
				(type default)
			)
			(layer "B.Fab")
		)
		(fp_line
			(start 1.1938 0.4064)
			(end 1.1938 -0.4064)
			(stroke
				(width 0.1)
				(type default)
			)
			(layer "B.Fab")
		)
		(fp_line
			(start -1.1938 -0.4064)
			(end -1.1938 0.4064)
			(stroke
				(width 0.1)
				(type default)
			)
			(layer "B.Fab")
		)
		(fp_line
			(start -0.8636 -0.4064)
			(end -1.1938 -0.4064)
			(stroke
				(width 0.1)
				(type default)
			)
			(layer "B.Fab")
		)
		(fp_line
			(start 0.8636 -0.4064)
			(end 0.8636 -0.4572)
			(stroke
				(width 0.1)
				(type default)
			)
			(layer "B.Fab")
		)
		(fp_line
			(start 1.1938 -0.4064)
			(end 0.8636 -0.4064)
			(stroke
				(width 0.1)
				(type default)
			)
			(layer "B.Fab")
		)
		(fp_line
			(start -0.8636 -0.4572)
			(end -0.8636 -0.4064)
			(stroke
				(width 0.1)
				(type default)
			)
			(layer "B.Fab")
		)
		(fp_line
			(start 0.8636 -0.4572)
			(end -0.8636 -0.4572)
			(stroke
				(width 0.1)
				(type default)
			)
			(layer "B.Fab")
		)
		(pad "1" smd rect
			(at 0.7366 0 180)
			(size 0.7112 0.8128)
			(layers "B.Cu" "B.Mask" "B.Paste")
			(net "PVNN_MAIN_CPU0")
		)
		(pad "2" smd rect
			(at -0.7366 0 180)
			(size 0.7112 0.8128)
			(layers "B.Cu" "B.Mask" "B.Paste")
			(net "GND")
		)
	)
	(footprint ""
		(layer "B.Cu")
		(at 25.277064 -175.824642 -90)
		(property "Reference" "R2584"
			(at 0 0 90)
			(layer "B.SilkS")
			(hide yes)
			(effects
				(font
					(size 1.27 1.27)
				)
				(justify mirror)
			)
		)
		(property "Value" ""
			(at 0 0 90)
			(layer "B.Fab")
			(effects
				(font
					(size 1.27 1.27)
				)
				(justify mirror)
			)
		)
		(duplicate_pad_numbers_are_jumpers no)
		(fp_line
			(start -0.7874 0.4064)
			(end 0.7874 0.4064)
			(stroke
				(width 0.1524)
				(type default)
			)
			(layer "B.SilkS")
		)
		(fp_line
			(start 0.7874 0.4064)
			(end 0.7874 -0.4064)
			(stroke
				(width 0.1524)
				(type default)
			)
			(layer "B.SilkS")
		)
		(fp_line
			(start -0.7874 -0.4064)
			(end -0.7874 0.4064)
			(stroke
				(width 0.1524)
				(type default)
			)
			(layer "B.SilkS")
		)
		(fp_line
			(start 0.7874 -0.4064)
			(end -0.7874 -0.4064)
			(stroke
				(width 0.1524)
				(type default)
			)
			(layer "B.SilkS")
		)
		(fp_line
			(start -0.67945 0.3048)
			(end -0.120396 0.3048)
			(stroke
				(width 0.1)
				(type default)
			)
			(layer "B.Fab")
		)
		(fp_line
			(start -0.120396 0.3048)
			(end -0.120396 0.2794)
			(stroke
				(width 0.1)
				(type default)
			)
			(layer "B.Fab")
		)
		(fp_line
			(start 0.12065 0.3048)
			(end 0.67945 0.3048)
			(stroke
				(width 0.1)
				(type default)
			)
			(layer "B.Fab")
		)
		(fp_line
			(start 0.67945 0.3048)
			(end 0.67945 -0.305054)
			(stroke
				(width 0.1)
				(type default)
			)
			(layer "B.Fab")
		)
		(fp_line
			(start -0.120396 0.2794)
			(end 0.12065 0.2794)
			(stroke
				(width 0.1)
				(type default)
			)
			(layer "B.Fab")
		)
		(fp_line
			(start 0.12065 0.2794)
			(end 0.12065 0.3048)
			(stroke
				(width 0.1)
				(type default)
			)
			(layer "B.Fab")
		)
		(fp_line
			(start -0.12065 -0.2794)
			(end -0.12065 -0.3048)
			(stroke
				(width 0.1)
				(type default)
			)
			(layer "B.Fab")
		)
		(fp_line
			(start 0.12065 -0.2794)
			(end -0.12065 -0.2794)
			(stroke
				(width 0.1)
				(type default)
			)
			(layer "B.Fab")
		)
		(fp_line
			(start -0.67945 -0.3048)
			(end -0.67945 0.3048)
			(stroke
				(width 0.1)
				(type default)
			)
			(layer "B.Fab")
		)
		(fp_line
			(start -0.12065 -0.3048)
			(end -0.67945 -0.3048)
			(stroke
				(width 0.1)
				(type default)
			)
			(layer "B.Fab")
		)
		(fp_line
			(start 0.12065 -0.305054)
			(end 0.12065 -0.2794)
			(stroke
				(width 0.1)
				(type default)
			)
			(layer "B.Fab")
		)
		(fp_line
			(start 0.67945 -0.305054)
			(end 0.12065 -0.305054)
			(stroke
				(width 0.1)
				(type default)
			)
			(layer "B.Fab")
		)
		(pad "1" smd circle
			(at 0.40005 0 90)
			(size 0 0)
			(layers "B.Cu" "B.Mask" "B.Paste")
			(net "P3V3_AUX")
		)
		(pad "2" smd circle
			(at -0.40005 0 90)
			(size 0 0)
			(layers "B.Cu" "B.Mask" "B.Paste")
			(net "PWRGD_PVNN_MAIN_CPU1_R")
		)
	)
	(footprint ""
		(layer "B.Cu")
		(at 368.398298 -359.586276 -90)
		(property "Reference" "PJ64"
			(at -3.236722 -3.587242 0)
			(unlocked yes)
			(layer "B.SilkS")
			(effects
				(font
					(size 0.7874 0.5842)
					(thickness 0.1524)
				)
				(justify left mirror)
			)
		)
		(property "Value" ""
			(at 0 0 90)
			(layer "B.Fab")
			(effects
				(font
					(size 1.27 1.27)
				)
				(justify mirror)
			)
		)
		(duplicate_pad_numbers_are_jumpers no)
		(pad "1" smd circle
			(at 0.7493 0)
			(size 0 0)
			(layers "B.Cu" "B.Mask" "B.Paste")
			(net "SH_PVPP_HBM_CPU0_P")
		)
		(pad "2" smd rect
			(at -0.7493 0 180)
			(size 0.7112 0.8128)
			(layers "B.Cu" "B.Mask" "B.Paste")
			(net "PVPP_HBM_CPU0")
		)
		(zone
			(layer "B.Cu")
			(hatch none 0.5)
			(connect_pads
				(clearance 0)
			)
			(min_thickness 0.25)
			(keepout
				(tracks allowed)
				(vias not_allowed)
				(pads allowed)
				(copperpour not_allowed)
				(footprints allowed)
			)
			(placement
				(enabled no)
				(sheetname "")
			)
			(fill
				(thermal_gap 0.5)
				(thermal_bridge_width 0.5)
				(island_removal_mode 0)
			)
			(polygon
				(pts
					(xy 367.987072 -358.405176) (xy 368.804698 -358.405176) (xy 368.804698 -360.792776) (xy 367.987072 -360.792776)
				)
			)
		)
	)
)
